# ZAIUS-MB-PVT-X04-BOM_X31_20180131_Final.xls.xlsx — TLA (bom)
| FOXCONN TECHNOLOGY GROUP |  |  |  |  |  |  |  |  |  |
| BILL OF MATERIAL |  |  |  |  |  |  |  |  |  |
| AA P/N | 1A42DLU00-600-G | CUSTOMER | <name> | Customer P/N | 42001726-05 | Product Code |  |  |  |
| PWA P/N |  | PWA DESCRIPTION | ASSY,MB,G_ZAIUS |  |  | PWA REV | PVT-X04 | Prepared By SE |  |
| Item | FOXCONN P/N | Customer P/N | Part Description | Manufacturer  Full Name | Manufacturer  Part Number | Qty | RoHS Status | Location | Remark |
| 1 | 1A424CJ00-600-G |  | LOAD FRAME ASM,ZNEW,IBM,01AF120,G,00 | FOXCONN / EPD5 | 1A424CJ00-600-G | 2 | G |  | Rev:A IBM PN:01AF120 |
| 2 | 1A424CG00-600-G |  | LOAD FRAME ASM,ZNEW,IBM,01AF118,G,00 | FOXCONN / EPD5 | 1A424CG00-600-G | 2 | G |  | Rev:A IBM PN:01AF118 |
| 3 | 2A584VU00-192-G |  | BACKPLATE SCREW | Supply Technologies | 46K4434 | 8 | G |  | Rev:A |
| 4 | 1A42FV700-13E-G |  | Power 9 CPU Backplate (Combined with Mylar and Dowel) | Aavid | 360493 | 2 | G |  | Rev:A (Reference IBM PN:01AF136) |
|  | 1A42FL600-H8U-G |  | Power 9 CPU Backplate (Combined with Mylar and Dowel) ; 2nd | Furukawa | HS855380 |  | G |  | Rev 01 and Rev B are the same can be common parts. Rev:01 |
| 5 | 7J-004-938 |  | L6 LABEL ( 12.7*11.1mm) | FOXCONN / EPD1 | 7J-004-938 | 1 | G |  | ID label. |
| 6 | 1A42EG100-653-G |  | Switch CAP blue. | DIPTRONICS | KTSC-62B | 1 | G |  | Rev:H Color Blue for Power button. |
| 7 | 1A42EGF00-653-G |  | Switch CAP black. | DIPTRONICS | KTSC-62K | 1 | G |  | Rev:H Color Black for Reset button. |
| 8 | 480124F00-13E-G |  | Heat sink (40x80x10 mm) | Aavid | 658031 | 2 | G |  | Rev:A For VTM-1 |
|  | 480124E00-H8U-G |  | Heat sink (40x80x10 mm) | Furukawa | HS855362 |  | G |  | Rev: 01 For VTM-1 |
| 9 | 480124G00-13E-G |  | Heat sink(80x57.3x15 mm) | Aavid | 658032 | 2 | G |  | Rev:A For VTM-2 |
|  | 480124D00-H8U-G |  | Heat sink(80x57.3x15 mm) | Furukawa | HS855372 |  | G |  | Rev:01 For VTM-2 |
| 10 | 2A3000M00-600-G |  | SPACER H:6.6MM, THICKNESS:3.2MM | KANG YANG | ULCO6.6-3.1(GR) | 1 | G |  | Rev:A1 FOR M.2 CARD |
| 11 | 2A3000K00-600-G |  | SPACER H:12MM, THICKNESS:3.2MM | KANG YANG | MSPN-12 | 4 | G |  | Rev:A FOR OCP CARD |
| 12 | 7J-004-1582 |  | Label 1.25" (31.75mm) x 0.5"(6.35mm) | FOXCONN / EPD1 | 7J-004-1582 | 2 | G |  | For customer PN & SN label requirement. |
| 13 | 7D115LM00-600-G |  | Rubber=12x4.6x7mm | PINGOOD | L120704MP-X3O | 2 | G |  | Rev:X01 For Heat sink VTM-2 |
| 14 | 7J-004-1027 |  | LBL,ADRS,MAC (16 x 16 mm) | FOXCONN / EPD1 | 7J-004-1027 | 1 | G |  | For LOM, BMC, NCSI |
| 15 | 7J-004-1618 |  | LBL,CPU Socket | Sunway | 7J-004-1618 | 2 | G |  | For CPU Socket |
| 16 | 7D115N900-600-G |  | 8_SILICON-FOAM-MB-MID-H_ZUS(6.35x70x10) | Foxconn-EPD5 | 7D115N900-600-G | 1 | G |  | Rev:X01 For MB Bottom side Sponge's Contact window: <name> |
| 17 | 7D115NA00-600-G |  | 8_SILICON-FOAM-MB-SIDE-H_ZUS (6.35x40x10) | Foxconn-EPD5 | 7D115NA00-600-G | 2 | G |  | Rev:X01 For MB Bottom side Sponge's Contact window: <name> |
| 18 | 7D115SJ00-600-G |  | 8_SILICON-FOAM-MB-CPU-HS_ZUS | Foxconn-EPD5 | 7D115SJ00-600-G | 4 | G |  | Rev:X1 For CPU HSK |
